(kicad_pcb
	(version 20241229)
	(generator "pcbnew")
	(generator_version "9.0")
	(general
		(thickness 1.711)
		(legacy_teardrops no)
	)
	(paper "A4")
	(title_block
		(title "Antmicro Baseboard for Jetson AGX Thor")
		(date "2026-02-18")
		(rev "1.1.0")
		(company "Antmicro Ltd")
		(comment 1 "www.antmicro.com")
		(comment 9 "footprints 1160-1163 of 1170")
	)
	(layers
		(0 "F.Cu" signal)
		(4 "In1.Cu" signal)
		(6 "In2.Cu" signal)
		(8 "In3.Cu" signal)
		(10 "In4.Cu" jumper)
		(12 "In5.Cu" signal)
		(14 "In6.Cu" signal)
		(16 "In7.Cu" signal)
		(18 "In8.Cu" signal)
		(2 "B.Cu" signal)
		(9 "F.Adhes" user "F.Adhesive")
		(11 "B.Adhes" user "B.Adhesive")
		(13 "F.Paste" user)
		(15 "B.Paste" user)
		(5 "F.SilkS" user "F.Silkscreen")
		(7 "B.SilkS" user "B.Silkscreen")
		(1 "F.Mask" user)
		(3 "B.Mask" user)
		(17 "Dwgs.User" user "User.Drawings")
		(19 "Cmts.User" user "User.Comments")
		(21 "Eco1.User" user "User.Eco1")
		(23 "Eco2.User" user "User.Eco2")
		(25 "Edge.Cuts" user)
		(27 "Margin" user)
		(31 "F.CrtYd" user "F.Courtyard")
		(29 "B.CrtYd" user "B.Courtyard")
		(35 "F.Fab" user)
		(33 "B.Fab" user)
	)
	(footprint "antmicro-footprints:R_0402_1005Metric"
		(layer "B.Cu")
		(at 61.6 86 -90)
		(descr "Resistor SMD 0402")
		(tags "resistor SMD 0402")
		(property "Reference" "R183"
			(at -1.73 -2.65 90)
			(layer "B.SilkS")
			(effects
				(font
					(size 0.7 0.7)
					(thickness 0.15)
				)
				(justify left bottom mirror)
			)
		)
		(property "Value" "R_470R_0402"
			(at -1.011843 -1.772046 90)
			(layer "B.Fab")
			(effects
				(font
					(size 0.7 0.7)
					(thickness 0.15)
				)
				(justify left bottom mirror)
			)
		)
		(property "Datasheet" "https://www.bourns.com/docs/product-datasheets/cr.pdf"
			(at 0 0 90)
			(layer "B.Fab")
			(hide yes)
			(effects
				(font
					(size 1.27 1.27)
					(thickness 0.15)
				)
				(justify mirror)
			)
		)
		(property "Description" "SMD Chip Resistor, 470 ohm, ± 1%, 62.5 mW, 0402 [1005 Metric], Thick Film, General Purpose"
			(at 0 0 90)
			(layer "B.Fab")
			(hide yes)
			(effects
				(font
					(size 1.27 1.27)
					(thickness 0.15)
				)
				(justify mirror)
			)
		)
		(property "Manufacturer" "Bourns"
			(at 0 0 90)
			(unlocked yes)
			(layer "B.Fab")
			(hide yes)
			(effects
				(font
					(size 1 1)
					(thickness 0.15)
				)
				(justify mirror)
			)
		)
		(property "MPN" "CR0402-FX-4700GLF"
			(at 0 0 90)
			(unlocked yes)
			(layer "B.Fab")
			(hide yes)
			(effects
				(font
					(size 1 1)
					(thickness 0.15)
				)
				(justify mirror)
			)
		)
		(property "Val" "470R"
			(at 0 0 90)
			(unlocked yes)
			(layer "B.Fab")
			(hide yes)
			(effects
				(font
					(size 1 1)
					(thickness 0.15)
				)
				(justify mirror)
			)
		)
		(property "License" "Apache-2.0"
			(at 0 0 90)
			(unlocked yes)
			(layer "B.Fab")
			(hide yes)
			(effects
				(font
					(size 1 1)
					(thickness 0.15)
				)
				(justify mirror)
			)
		)
		(property "Author" "Antmicro"
			(at 0 0 90)
			(unlocked yes)
			(layer "B.Fab")
			(hide yes)
			(effects
				(font
					(size 1 1)
					(thickness 0.15)
				)
				(justify mirror)
			)
		)
		(property "Tolerance" "1%"
			(at 0 0 90)
			(unlocked yes)
			(layer "B.Fab")
			(hide yes)
			(effects
				(font
					(size 1 1)
					(thickness 0.15)
				)
				(justify mirror)
			)
		)
		(sheetname "/CSI/")
		(sheetfile "csi.kicad_sch")
		(attr smd)
		(fp_poly
			(pts
				(xy -0.925 0.47) (xy 0.925 0.47) (xy 0.925 -0.47) (xy -0.925 -0.47)
			)
			(stroke
				(width 0.05)
				(type default)
			)
			(fill no)
			(layer "B.CrtYd")
		)
		(fp_poly
			(pts
				(xy -0.5 0.25) (xy 0.5 0.25) (xy 0.5 -0.25) (xy -0.5 -0.25)
			)
			(stroke
				(width 0.15)
				(type solid)
			)
			(fill no)
			(layer "B.Fab")
		)
		(fp_text user "License: Apache-2.0"
			(at -0.949999 -5.169 90)
			(layer "B.Fab")
			(effects
				(font
					(size 0.7 0.7)
					(thickness 0.15)
				)
				(justify left bottom mirror)
			)
		)
		(fp_text user "Author: Antmicro"
			(at -0.95 -4.169 90)
			(layer "B.Fab")
			(effects
				(font
					(size 0.7 0.7)
					(thickness 0.15)
				)
				(justify left bottom mirror)
			)
		)
		(fp_text user "${REFERENCE}"
			(at -0.95 -3.168 90)
			(layer "B.Fab")
			(effects
				(font
					(size 0.7 0.7)
					(thickness 0.15)
				)
				(justify left bottom mirror)
			)
		)
		(pad "1" smd roundrect
			(at -0.48 0 270)
			(size 0.59 0.64)
			(layers "B.Cu" "B.Mask" "B.Paste")
			(roundrect_rratio 0.25)
			(net 542 "Net-(D29-A)")
			(pintype "passive")
		)
		(pad "2" smd roundrect
			(at 0.48 0 270)
			(size 0.59 0.64)
			(layers "B.Cu" "B.Mask" "B.Paste")
			(roundrect_rratio 0.25)
			(net 7 "/CSI/CSIA_5V")
			(pintype "passive")
		)
	)
	(footprint "antmicro-footprints:SOT-523"
		(layer "B.Cu")
		(at 160.21 62.79 -90)
		(property "Reference" "Q28"
			(at 4.21 6.91 270)
			(layer "B.SilkS")
			(effects
				(font
					(size 0.7 0.7)
					(thickness 0.15)
				)
				(justify left bottom mirror)
			)
		)
		(property "Value" "DMG1012T-7"
			(at 0.1 -1.824 90)
			(layer "B.Fab")
			(effects
				(font
					(size 0.7 0.7)
					(thickness 0.15)
				)
				(justify left bottom mirror)
			)
		)
		(property "Datasheet" "https://www.diodes.com/assets/Datasheets/ds31783.pdf"
			(at 0 0 90)
			(layer "B.Fab")
			(hide yes)
			(effects
				(font
					(size 1.27 1.27)
					(thickness 0.15)
				)
				(justify mirror)
			)
		)
		(property "Description" "Power MOSFET, N Channel, 20 V, 630 mA, 0.3 ohm, SOT-523, Surface Mount"
			(at 0 0 90)
			(layer "B.Fab")
			(hide yes)
			(effects
				(font
					(size 1.27 1.27)
					(thickness 0.15)
				)
				(justify mirror)
			)
		)
		(property "MPN" "DMG1012T-7"
			(at 0 0 90)
			(unlocked yes)
			(layer "B.Fab")
			(hide yes)
			(effects
				(font
					(size 1 1)
					(thickness 0.15)
				)
				(justify mirror)
			)
		)
		(property "Manufacturer" "Diodes Incorporated"
			(at 0 0 90)
			(unlocked yes)
			(layer "B.Fab")
			(hide yes)
			(effects
				(font
					(size 1 1)
					(thickness 0.15)
				)
				(justify mirror)
			)
		)
		(property "Author" "Antmicro"
			(at 0 0 90)
			(unlocked yes)
			(layer "B.Fab")
			(hide yes)
			(effects
				(font
					(size 1 1)
					(thickness 0.15)
				)
				(justify mirror)
			)
		)
		(property "License" "Apache-2.0"
			(at 0 0 90)
			(unlocked yes)
			(layer "B.Fab")
			(hide yes)
			(effects
				(font
					(size 1 1)
					(thickness 0.15)
				)
				(justify mirror)
			)
		)
		(sheetname "/SoM_IO2/")
		(sheetfile "som_io2.kicad_sch")
		(attr smd exclude_from_pos_files exclude_from_bom dnp)
		(fp_line
			(start -0.725 0.551)
			(end -0.277 0.551)
			(stroke
				(width 0.15)
				(type solid)
			)
			(layer "B.SilkS")
		)
		(fp_line
			(start -0.277 0.551)
			(end -0.277 0.75)
			(stroke
				(width 0.15)
				(type solid)
			)
			(layer "B.SilkS")
		)
		(fp_line
			(start -0.927 0.351)
			(end -0.725 0.551)
			(stroke
				(width 0.15)
				(type solid)
			)
			(layer "B.SilkS")
		)
		(fp_line
			(start -0.927 0.051)
			(end -0.927 0.351)
			(stroke
				(width 0.15)
				(type solid)
			)
			(layer "B.SilkS")
		)
		(fp_circle
			(center -0.9652 -0.9652)
			(end -0.9152 -0.9652)
			(stroke
				(width 0.15)
				(type solid)
			)
			(fill yes)
			(layer "B.SilkS")
		)
		(fp_line
			(start -1.12 1.16)
			(end 1.1 1.16)
			(stroke
				(width 0.05)
				(type solid)
			)
			(layer "B.CrtYd")
		)
		(fp_line
			(start -1.12 1.16)
			(end -1.12 -1.15)
			(stroke
				(width 0.05)
				(type solid)
			)
			(layer "B.CrtYd")
		)
		(fp_line
			(start 1.1 1.16)
			(end 1.1 -1.15)
			(stroke
				(width 0.05)
				(type solid)
			)
			(layer "B.CrtYd")
		)
		(fp_line
			(start -1.12 -1.15)
			(end 1.1 -1.15)
			(stroke
				(width 0.05)
				(type solid)
			)
			(layer "B.CrtYd")
		)
		(fp_line
			(start -0.652 0.425)
			(end -0.802 0.276)
			(stroke
				(width 0.15)
				(type solid)
			)
			(layer "B.Fab")
		)
		(fp_line
			(start 0.8 0.425)
			(end -0.652 0.425)
			(stroke
				(width 0.15)
				(type solid)
			)
			(layer "B.Fab")
		)
		(fp_line
			(start 0.8 0.425)
			(end 0.8 -0.424)
			(stroke
				(width 0.15)
				(type solid)
			)
			(layer "B.Fab")
		)
		(fp_line
			(start -0.802 0.276)
			(end -0.802 -0.424)
			(stroke
				(width 0.15)
				(type solid)
			)
			(layer "B.Fab")
		)
		(fp_line
			(start 0.8 -0.424)
			(end -0.802 -0.424)
			(stroke
				(width 0.15)
				(type solid)
			)
			(layer "B.Fab")
		)
		(fp_circle
			(center -0.9652 -0.9652)
			(end -0.9144 -0.9652)
			(stroke
				(width 0.15)
				(type solid)
			)
			(fill no)
			(layer "B.Fab")
		)
		(fp_text user "Author: Antmicro"
			(at -1.12 -6.224 90)
			(layer "B.Fab")
			(effects
				(font
					(size 0.7 0.7)
					(thickness 0.15)
				)
				(justify left bottom mirror)
			)
		)
		(fp_text user "License: Apache-2.0"
			(at -1.12 -5.024 90)
			(layer "B.Fab")
			(effects
				(font
					(size 0.7 0.7)
					(thickness 0.15)
				)
				(justify left bottom mirror)
			)
		)
		(fp_text user "${REFERENCE}"
			(at -1.12 -3.824 90)
			(layer "B.Fab")
			(effects
				(font
					(size 0.7 0.7)
					(thickness 0.15)
				)
				(justify left bottom mirror)
			)
		)
		(pad "1" smd rect
			(at -0.5 -0.65 270)
			(size 0.4 0.51)
			(layers "B.Cu" "B.Mask" "B.Paste")
			(net 1299 "Net-(Q28-G)")
			(pinfunction "G")
			(pintype "input")
		)
		(pad "2" smd rect
			(at 0.498 -0.65 270)
			(size 0.4 0.51)
			(layers "B.Cu" "B.Mask" "B.Paste")
			(net 1 "GND")
			(pinfunction "S")
			(pintype "passive")
		)
		(pad "3" smd rect
			(at 0 0.652 270)
			(size 0.4 0.51)
			(layers "B.Cu" "B.Mask" "B.Paste")
			(net 627 "/SoM_IO2/JTAG_TRST_N")
			(pinfunction "D")
			(pintype "passive")
		)
	)
	(footprint "antmicro-footprints:TSOT23-6"
		(layer "B.Cu")
		(at 233.8 81.8)
		(property "Reference" "U40"
			(at 2.9 -1.229 90)
			(layer "B.SilkS")
			(effects
				(font
					(size 0.7 0.7)
					(thickness 0.15)
				)
				(justify left bottom mirror)
			)
		)
		(property "Value" "AP22615A_TSOT26"
			(at 0 -2.600001 0)
			(layer "B.Fab")
			(effects
				(font
					(size 0.7 0.7)
					(thickness 0.15)
				)
				(justify right top mirror)
			)
		)
		(property "Datasheet" "https://www.mouser.com/datasheet/2/115/DIOD_S_A0008958405_1-2543193.pdf"
			(at 0 0 0)
			(layer "B.Fab")
			(hide yes)
			(effects
				(font
					(size 1.27 1.27)
					(thickness 0.15)
				)
				(justify mirror)
			)
		)
		(property "Description" "Power Load Distribution Switch, High Side, Active High, 1 Output, 5.5 V, 3.6 A, 0.04 ohm, TSOT-26-6"
			(at 0 0 0)
			(layer "B.Fab")
			(hide yes)
			(effects
				(font
					(size 1.27 1.27)
					(thickness 0.15)
				)
				(justify mirror)
			)
		)
		(property "MPN" "AP22615AWU-7"
			(at 0 0 180)
			(unlocked yes)
			(layer "B.Fab")
			(hide yes)
			(effects
				(font
					(size 1 1)
					(thickness 0.15)
				)
				(justify mirror)
			)
		)
		(property "Manufacturer" "Diodes Incorporated"
			(at 0 0 180)
			(unlocked yes)
			(layer "B.Fab")
			(hide yes)
			(effects
				(font
					(size 1 1)
					(thickness 0.15)
				)
				(justify mirror)
			)
		)
		(property "Author" "Antmicro"
			(at 0 0 180)
			(unlocked yes)
			(layer "B.Fab")
			(hide yes)
			(effects
				(font
					(size 1 1)
					(thickness 0.15)
				)
				(justify mirror)
			)
		)
		(property "License" "Apache-2.0"
			(at 0 0 180)
			(unlocked yes)
			(layer "B.Fab")
			(hide yes)
			(effects
				(font
					(size 1 1)
					(thickness 0.15)
				)
				(justify mirror)
			)
		)
		(sheetname "/USB Debug, PD/")
		(sheetfile "usb_debug_pd.kicad_sch")
		(attr smd)
		(fp_line
			(start -1 -1.55)
			(end -1 -1.4)
			(stroke
				(width 0.15)
				(type solid)
			)
			(layer "B.SilkS")
		)
		(fp_line
			(start -1 1.5)
			(end -1 1.375)
			(stroke
				(width 0.15)
				(type solid)
			)
			(layer "B.SilkS")
		)
		(fp_line
			(start 1 -1.55)
			(end -1 -1.55)
			(stroke
				(width 0.15)
				(type solid)
			)
			(layer "B.SilkS")
		)
		(fp_line
			(start 1 -1.55)
			(end 1 -1.4)
			(stroke
				(width 0.15)
				(type solid)
			)
			(layer "B.SilkS")
		)
		(fp_line
			(start 1 1.497)
			(end -1 1.5)
			(stroke
				(width 0.15)
				(type solid)
			)
			(layer "B.SilkS")
		)
		(fp_line
			(start 1 1.497)
			(end 1 1.375)
			(stroke
				(width 0.15)
				(type solid)
			)
			(layer "B.SilkS")
		)
		(fp_circle
			(center -1.44 1.5)
			(end -1.39 1.5)
			(stroke
				(width 0.15)
				(type solid)
			)
			(fill yes)
			(layer "B.SilkS")
		)
		(fp_poly
			(pts
				(xy 1.930001 1.7) (xy 1.930001 -1.7) (xy -1.930001 -1.7) (xy -1.930001 1.7)
			)
			(stroke
				(width 0.05)
				(type solid)
			)
			(fill no)
			(layer "B.CrtYd")
		)
		(fp_line
			(start -0.45 1.520999)
			(end -0.876001 1.096)
			(stroke
				(width 0.15)
				(type solid)
			)
			(layer "B.Fab")
		)
		(fp_poly
			(pts
				(xy 0.875 -1.528) (xy 0.875 1.525) (xy -0.875 1.525) (xy -0.875 -1.528)
			)
			(stroke
				(width 0.15)
				(type solid)
			)
			(fill no)
			(layer "B.Fab")
		)
		(fp_text user "${REFERENCE}"
			(at -1.93 -3.8 0)
			(layer "B.Fab")
			(effects
				(font
					(size 0.7 0.7)
					(thickness 0.15)
				)
				(justify right top mirror)
			)
		)
		(fp_text user "License: Apache-2.0"
			(at -1.93 -6.199 0)
			(layer "B.Fab")
			(effects
				(font
					(size 0.7 0.7)
					(thickness 0.15)
				)
				(justify right top mirror)
			)
		)
		(fp_text user "Author: Antmicro"
			(at -1.93 -5 0)
			(layer "B.Fab")
			(effects
				(font
					(size 0.7 0.7)
					(thickness 0.15)
				)
				(justify right top mirror)
			)
		)
		(pad "1" smd rect
			(at -1.301 0.947 90)
			(size 0.7 1.2)
			(layers "B.Cu" "B.Mask" "B.Paste")
			(net 176 "/USB Debug, PD/USBC0_VBUS")
			(pinfunction "OUT")
			(pintype "power_out")
		)
		(pad "2" smd rect
			(at -1.300999 -0.004 90)
			(size 0.7 1.2)
			(layers "B.Cu" "B.Mask" "B.Paste")
			(net 1 "GND")
			(pinfunction "GND")
			(pintype "power_in")
		)
		(pad "3" smd rect
			(at -1.301 -0.954 90)
			(size 0.7 1.2)
			(layers "B.Cu" "B.Mask" "B.Paste")
			(net 976 "/USB Debug, PD/USBC0_FLG")
			(pinfunction "FLG")
			(pintype "output")
		)
		(pad "4" smd rect
			(at 1.299 -0.954 90)
			(size 0.7 1.2)
			(layers "B.Cu" "B.Mask" "B.Paste")
			(net 977 "Net-(U40-EN)")
			(pinfunction "EN")
			(pintype "input")
		)
		(pad "5" smd rect
			(at 1.299 -0.004 90)
			(size 0.7 1.2)
			(layers "B.Cu" "B.Mask" "B.Paste")
			(net 978 "/USB Debug, PD/USBC0_ISET")
			(pinfunction "ISET")
			(pintype "passive")
		)
		(pad "6" smd rect
			(at 1.299 0.947 90)
			(size 0.7 1.2)
			(layers "B.Cu" "B.Mask" "B.Paste")
			(net 5 "+5V")
			(pinfunction "IN")
			(pintype "power_in")
		)
	)
	(footprint "antmicro-footprints:C_0402_1005Metric"
		(layer "B.Cu")
		(at 91.180001 103.6 -90)
		(descr "Capacitor SMD 0402")
		(tags "capacitor SMD 0402")
		(property "Reference" "C331"
			(at -3.8 -0.419999 90)
			(layer "B.SilkS")
			(effects
				(font
					(size 0.7 0.7)
					(thickness 0.15)
				)
				(justify left bottom mirror)
			)
		)
		(property "Value" "C_100n_0402"
			(at -1.022927 -2.155213 90)
			(layer "B.Fab")
			(effects
				(font
					(size 0.7 0.7)
					(thickness 0.15)
				)
				(justify left bottom mirror)
			)
		)
		(property "Datasheet" "https://www.murata.com/products/productdetail?partno=GRM155R61H104KE14%23"
			(at 0 0 90)
			(layer "B.Fab")
			(hide yes)
			(effects
				(font
					(size 1.27 1.27)
					(thickness 0.15)
				)
				(justify mirror)
			)
		)
		(property "Description" "SMD Multilayer Ceramic Capacitor, 0.1 µF, 50 V, 0402 [1005 Metric], ± 10%, X5R, GRM Series"
			(at 0 0 90)
			(layer "B.Fab")
			(hide yes)
			(effects
				(font
					(size 1.27 1.27)
					(thickness 0.15)
				)
				(justify mirror)
			)
		)
		(property "Manufacturer" "Murata"
			(at 0 0 90)
			(unlocked yes)
			(layer "B.Fab")
			(hide yes)
			(effects
				(font
					(size 1 1)
					(thickness 0.15)
				)
				(justify mirror)
			)
		)
		(property "MPN" "GRM155R61H104KE14D"
			(at 0 0 90)
			(unlocked yes)
			(layer "B.Fab")
			(hide yes)
			(effects
				(font
					(size 1 1)
					(thickness 0.15)
				)
				(justify mirror)
			)
		)
		(property "Val" "100n"
			(at 0 0 90)
			(unlocked yes)
			(layer "B.Fab")
			(hide yes)
			(effects
				(font
					(size 1 1)
					(thickness 0.15)
				)
				(justify mirror)
			)
		)
		(property "License" "Apache-2.0"
			(at 0 0 90)
			(unlocked yes)
			(layer "B.Fab")
			(hide yes)
			(effects
				(font
					(size 1 1)
					(thickness 0.15)
				)
				(justify mirror)
			)
		)
		(property "Author" "Antmicro"
			(at 0 0 90)
			(unlocked yes)
			(layer "B.Fab")
			(hide yes)
			(effects
				(font
					(size 1 1)
					(thickness 0.15)
				)
				(justify mirror)
			)
		)
		(property "Voltage" "50V"
			(at 0 0 90)
			(unlocked yes)
			(layer "B.Fab")
			(hide yes)
			(effects
				(font
					(size 1 1)
					(thickness 0.15)
				)
				(justify mirror)
			)
		)
		(property "Dielectric" "X5R"
			(at 0 0 90)
			(unlocked yes)
			(layer "B.Fab")
			(hide yes)
			(effects
				(font
					(size 1 1)
					(thickness 0.15)
				)
				(justify mirror)
			)
		)
		(sheetname "/SoM_IO2/")
		(sheetfile "som_io2.kicad_sch")
		(attr smd)
		(fp_poly
			(pts
				(xy -0.925 0.47) (xy 0.925 0.47) (xy 0.925 -0.47) (xy -0.925 -0.47)
			)
			(stroke
				(width 0.05)
				(type default)
			)
			(fill no)
			(layer "B.CrtYd")
		)
		(fp_line
			(start -0.494 0.25)
			(end 0.504 0.25)
			(stroke
				(width 0.15)
				(type solid)
			)
			(layer "B.Fab")
		)
		(fp_line
			(start 0.504 0.25)
			(end 0.504 -0.248)
			(stroke
				(width 0.15)
				(type solid)
			)
			(layer "B.Fab")
		)
		(fp_line
			(start -0.494 -0.248)
			(end -0.494 0.25)
			(stroke
				(width 0.15)
				(type solid)
			)
			(layer "B.Fab")
		)
		(fp_line
			(start 0.504 -0.248)
			(end -0.494 -0.248)
			(stroke
				(width 0.15)
				(type solid)
			)
			(layer "B.Fab")
		)
		(fp_text user "${REFERENCE}"
			(at -0.939 -4.599 90)
			(layer "B.Fab")
			(effects
				(font
					(size 0.7 0.7)
					(thickness 0.15)
				)
				(justify left bottom mirror)
			)
		)
		(fp_text user "Author: Antmicro"
			(at -0.939 -3.399 90)
			(layer "B.Fab")
			(effects
				(font
					(size 0.7 0.7)
					(thickness 0.15)
				)
				(justify left bottom mirror)
			)
		)
		(fp_text user "License: Apache-2.0"
			(at -0.939 -5.799 90)
			(layer "B.Fab")
			(effects
				(font
					(size 0.7 0.7)
					(thickness 0.15)
				)
				(justify left bottom mirror)
			)
		)
		(pad "1" smd roundrect
			(at -0.48 0 270)
			(size 0.59 0.64)
			(layers "B.Cu" "B.Mask" "B.Paste")
			(roundrect_rratio 0.25)
			(net 682 "/Expansion connector/DP1.TX3-")
			(pintype "passive")
		)
		(pad "2" smd roundrect
			(at 0.48 0 270)
			(size 0.59 0.64)
			(layers "B.Cu" "B.Mask" "B.Paste")
			(roundrect_rratio 0.25)
			(net 1251 "/SoM_IO2/DP1.TX3_C-")
			(pintype "passive")
		)
	)
)
